(kicad_pcb
	(version 20260206)
	(generator "pcbnew")
	(generator_version "10.0")
	(general
		(thickness 1.6)
		(legacy_teardrops no)
	)
	(paper "A4")
	(title_block
		(title "Bryce Canyon_R.DPB_16317-1_OCP.brd")
		(comment 1 "Bryce Canyon / footprints 406-408 of 2099")
	)
	(layers
		(0 "F.Cu" signal "TOP")
		(4 "In1.Cu" signal "L2GND")
		(6 "In2.Cu" signal "L3")
		(8 "In3.Cu" signal "L4VCC")
		(10 "In4.Cu" signal "L5VCC")
		(12 "In5.Cu" signal "L6")
		(14 "In6.Cu" signal "L7GND")
		(2 "B.Cu" signal "BOTTOM")
		(9 "F.Adhes" user "F.Adhesive")
		(11 "B.Adhes" user "B.Adhesive")
		(13 "F.Paste" user "Package Geometry/Pastemask Top")
		(15 "B.Paste" user "Package Geometry/Pastemask Bottom")
		(5 "F.SilkS" user "Ref Des/Silkscreen Top")
		(7 "B.SilkS" user "Ref Des/Silkscreen Bottom")
		(1 "F.Mask" user "Board Geometry/Soldermask Top")
		(3 "B.Mask" user "Board Geometry/Soldermask Bottom")
		(17 "Dwgs.User" user "User.Drawings")
		(19 "Cmts.User" user "User.Comments")
		(21 "Eco1.User" user "User.Eco1")
		(23 "Eco2.User" user "User.Eco2")
		(25 "Edge.Cuts" user "Board Geometry/Outline")
		(27 "Margin" user)
		(31 "F.CrtYd" user "Package Geometry/Place Bound Top")
		(29 "B.CrtYd" user "Package Geometry/Place Bound Bottom")
		(35 "F.Fab" user "Ref Des/Assembly Top")
		(33 "B.Fab" user "Ref Des/Assembly Bottom")
	)
	(footprint ""
		(layer "F.Cu")
		(at 159.639 -371.602 180)
		(property "Reference" "R933"
			(at 0 0 180)
			(layer "F.SilkS")
			(hide yes)
			(effects
				(font
					(size 1.27 1.27)
				)
			)
		)
		(property "Value" "100KR2F-L1-GP"
			(at 0.064008 -3.993896 180)
			(unlocked yes)
			(layer "F.Fab")
			(hide yes)
			(effects
				(font
					(size 1.016 1.016)
					(thickness 0.1524)
				)
			)
		)
		(property "Device Type" "R402H16"
			(at 0.064008 -5.517896 180)
			(unlocked yes)
			(layer "F.Fab")
			(hide yes)
			(effects
				(font
					(size 1.016 1.016)
					(thickness 0.1524)
				)
			)
		)
		(duplicate_pad_numbers_are_jumpers no)
		(fp_line
			(start 0.508 -0.9398)
			(end -0.508 -0.9398)
			(stroke
				(width 0.1524)
				(type default)
			)
			(layer "F.SilkS")
		)
		(fp_line
			(start -0.508 -0.9398)
			(end -0.508 0.9398)
			(stroke
				(width 0.1524)
				(type default)
			)
			(layer "F.SilkS")
		)
		(fp_rect
			(start -0.508 0.9398)
			(end 0.508 -0.9398)
			(stroke
				(width 0)
				(type default)
			)
			(fill no)
			(layer "F.CrtYd")
		)
		(fp_rect
			(start -0.508 0.9398)
			(end 0.508 -0.9398)
			(stroke
				(width 0)
				(type default)
			)
			(fill no)
			(layer "F.Fab")
		)
		(pad "1" smd custom
			(at 0 -0.4445 180)
			(size 0.1397 0.1397)
			(layers "F.Cu" "F.Mask" "F.Paste")
			(net "P3V3_IN")
			(options
				(clearance outline)
				(anchor circle)
			)
			(primitives
				(gr_poly
					(pts
						(arc
							(start -0.1778 -0.2794)
							(mid -0.249642 -0.249642)
							(end -0.2794 -0.1778)
						)
						(arc
							(start -0.2794 0.1778)
							(mid -0.249642 0.249642)
							(end -0.1778 0.2794)
						)
						(arc
							(start 0.1778 0.2794)
							(mid 0.249642 0.249642)
							(end 0.2794 0.1778)
						)
						(arc
							(start 0.2794 -0.1778)
							(mid 0.249642 -0.249642)
							(end 0.1778 -0.2794)
						)
					)
					(width 0)
					(fill yes)
				)
			)
		)
		(pad "2" smd custom
			(at 0 0.4445 180)
			(size 0.1397 0.1397)
			(layers "F.Cu" "F.Mask" "F.Paste")
			(net "FAN_1_INS_N")
			(options
				(clearance outline)
				(anchor circle)
			)
			(primitives
				(gr_poly
					(pts
						(arc
							(start -0.1778 -0.2794)
							(mid -0.249642 -0.249642)
							(end -0.2794 -0.1778)
						)
						(arc
							(start -0.2794 0.1778)
							(mid -0.249642 0.249642)
							(end -0.1778 0.2794)
						)
						(arc
							(start 0.1778 0.2794)
							(mid 0.249642 0.249642)
							(end 0.2794 0.1778)
						)
						(arc
							(start 0.2794 -0.1778)
							(mid 0.249642 -0.249642)
							(end 0.1778 -0.2794)
						)
					)
					(width 0)
					(fill yes)
				)
			)
		)
	)
	(footprint ""
		(layer "F.Cu")
		(at 122.849894 -28.910026 -90)
		(property "Reference" "HDDSAS27"
			(at 0 0 270)
			(layer "F.SilkS")
			(hide yes)
			(effects
				(font
					(size 1.27 1.27)
				)
			)
		)
		(property "Value" "SKT-SAS15P-14P-45-GP"
			(at -20.7645 -8.9789 270)
			(unlocked yes)
			(layer "F.Fab")
			(hide yes)
			(effects
				(font
					(size 1.016 1.016)
					(thickness 0.1524)
				)
			)
		)
		(property "Device Type" "10120818-001C-TRLF"
			(at -20.7645 -10.5029 270)
			(unlocked yes)
			(layer "F.Fab")
			(hide yes)
			(effects
				(font
					(size 1.016 1.016)
					(thickness 0.1524)
				)
			)
		)
		(duplicate_pad_numbers_are_jumpers no)
		(fp_line
			(start 1.651 4.2926)
			(end 1.651 3.0099)
			(stroke
				(width 0.1524)
				(type default)
			)
			(layer "F.SilkS")
		)
		(fp_line
			(start 8.509 4.2926)
			(end 1.651 4.2926)
			(stroke
				(width 0.1524)
				(type default)
			)
			(layer "F.SilkS")
		)
		(fp_line
			(start -23.4188 3.0099)
			(end -23.4188 -3.2512)
			(stroke
				(width 0.1524)
				(type default)
			)
			(layer "F.SilkS")
		)
		(fp_line
			(start 1.651 3.0099)
			(end -23.4188 3.0099)
			(stroke
				(width 0.1524)
				(type default)
			)
			(layer "F.SilkS")
		)
		(fp_line
			(start 8.509 3.0099)
			(end 8.509 4.2926)
			(stroke
				(width 0.1524)
				(type default)
			)
			(layer "F.SilkS")
		)
		(fp_line
			(start 23.4188 3.0099)
			(end 8.509 3.0099)
			(stroke
				(width 0.1524)
				(type default)
			)
			(layer "F.SilkS")
		)
		(fp_line
			(start -23.4188 -3.2512)
			(end 23.4188 -3.2512)
			(stroke
				(width 0.1524)
				(type default)
			)
			(layer "F.SilkS")
		)
		(fp_line
			(start 23.4188 -3.2512)
			(end 23.4188 3.0099)
			(stroke
				(width 0.1524)
				(type default)
			)
			(layer "F.SilkS")
		)
		(fp_line
			(start 15.5067 -3.3401)
			(end 16.2687 -3.3401)
			(stroke
				(width 0.3302)
				(type default)
			)
			(layer "F.SilkS")
		)
		(fp_poly
			(pts
				(xy 15.868904 -3.230372) (xy 16.503904 -3.865372) (xy 15.233904 -3.865372)
			)
			(stroke
				(width 0)
				(type default)
			)
			(fill yes)
			(layer "F.SilkS")
		)
		(fp_poly
			(pts
				(xy -22.8727 -2.7559) (xy 22.8727 -2.7559) (xy 22.8727 2.7559) (xy 8.255 2.7559) (xy 8.255 3.5179)
				(xy 1.905 3.5179) (xy 1.905 2.7559) (xy -22.8727 2.7559)
			)
			(stroke
				(width 0)
				(type default)
			)
			(fill no)
			(layer "F.CrtYd")
		)
		(fp_poly
			(pts
				(xy 1.397 4.5466) (xy 1.397 3.2639) (xy -23.6728 3.2639) (xy -23.6728 -3.5052) (xy 23.6728 -3.5052)
				(xy 23.6728 -0.00635) (xy 22.8727 -0.00635) (xy 22.8727 -2.7559) (xy -22.8727 -2.7559) (xy -22.8727 2.7559)
				(xy 1.905 2.7559) (xy 1.905 3.5179) (xy 8.255 3.5179) (xy 8.255 2.7559) (xy 22.8727 2.7559) (xy 22.8727 0.00635)
				(xy 23.6728 0.00635) (xy 23.6728 3.2639) (xy 8.763 3.2639) (xy 8.763 4.5466)
			)
			(stroke
				(width 0)
				(type default)
			)
			(fill no)
			(layer "F.CrtYd")
		)
		(fp_poly
			(pts
				(xy 1.397 4.5466) (xy 1.397 3.2639) (xy -23.6728 3.2639) (xy -23.6728 -3.5052) (xy 23.6728 -3.5052)
				(xy 23.6728 3.2639) (xy 8.763 3.2639) (xy 8.763 4.5466)
			)
			(stroke
				(width 0)
				(type default)
			)
			(fill no)
			(layer "F.Fab")
		)
		(pad "" np_thru_hole circle
			(at -18.874994 0 270)
			(size 0.254 0.254)
			(drill 1.3462)
			(layers "*.Cu" "*.Mask")
			(clearance 0.9017)
			(thermal_gap 0.9017)
		)
		(pad "" np_thru_hole circle
			(at 18.874994 0 270)
			(size 0.254 0.254)
			(drill 0.9398)
			(layers "*.Cu" "*.Mask")
			(clearance 0.6985)
			(thermal_gap 0.6985)
		)
		(pad "G1" smd rect
			(at 21.874988 0 270)
			(size 2.5908 2.5908)
			(layers "F.Cu" "F.Mask" "F.Paste")
			(net "GND")
		)
		(pad "G2" smd rect
			(at -21.874988 0 270)
			(size 2.5908 2.5908)
			(layers "F.Cu" "F.Mask" "F.Paste")
			(net "GND")
		)
		(pad "P1" smd rect
			(at 1.905 -1.82499 270)
			(size 0.6096 2.3622)
			(layers "F.Cu" "F.Mask" "F.Paste")
			(net "Net_1664")
		)
		(pad "P2" smd rect
			(at 0.635 -1.82499 270)
			(size 0.6096 2.3622)
			(layers "F.Cu" "F.Mask" "F.Paste")
			(net "Net_1665")
		)
		(pad "P3" smd rect
			(at -0.635 -1.82499 270)
			(size 0.6096 2.3622)
			(layers "F.Cu" "F.Mask" "F.Paste")
			(net "Net_1666")
		)
		(pad "P4" smd rect
			(at -1.905 -1.82499 270)
			(size 0.6096 2.3622)
			(layers "F.Cu" "F.Mask" "F.Paste")
			(net "GND")
		)
		(pad "P5" smd rect
			(at -3.175 -1.82499 270)
			(size 0.6096 2.3622)
			(layers "F.Cu" "F.Mask" "F.Paste")
			(net "HDD_PRSNT_27")
		)
		(pad "P6" smd rect
			(at -4.445 -1.82499 270)
			(size 0.6096 2.3622)
			(layers "F.Cu" "F.Mask" "F.Paste")
			(net "GND")
		)
		(pad "P7" smd rect
			(at -5.715 -1.82499 270)
			(size 0.6096 2.3622)
			(layers "F.Cu" "F.Mask" "F.Paste")
			(net "5V_PRE_27")
		)
		(pad "P8" smd rect
			(at -6.985 -1.82499 270)
			(size 0.6096 2.3622)
			(layers "F.Cu" "F.Mask" "F.Paste")
			(net "P5V_HDD27")
		)
		(pad "P9" smd rect
			(at -8.255 -1.82499 270)
			(size 0.6096 2.3622)
			(layers "F.Cu" "F.Mask" "F.Paste")
			(net "P5V_HDD27")
		)
		(pad "P10" smd rect
			(at -9.525 -1.82499 270)
			(size 0.6096 2.3622)
			(layers "F.Cu" "F.Mask" "F.Paste")
			(net "GND")
		)
		(pad "P11" smd rect
			(at -10.795 -1.82499 270)
			(size 0.6096 2.3622)
			(layers "F.Cu" "F.Mask" "F.Paste")
			(net "ACT_HDD_27")
		)
		(pad "P12" smd rect
			(at -12.065 -1.82499 270)
			(size 0.6096 2.3622)
			(layers "F.Cu" "F.Mask" "F.Paste")
			(net "GND")
		)
		(pad "P13" smd rect
			(at -13.335 -1.82499 270)
			(size 0.6096 2.3622)
			(layers "F.Cu" "F.Mask" "F.Paste")
			(net "12V_PRE_27")
		)
		(pad "P14" smd rect
			(at -14.605 -1.82499 270)
			(size 0.6096 2.3622)
			(layers "F.Cu" "F.Mask" "F.Paste")
			(net "P12V_HDD27")
		)
		(pad "P15" smd rect
			(at -15.875 -1.82499 270)
			(size 0.6096 2.3622)
			(layers "F.Cu" "F.Mask" "F.Paste")
			(net "P12V_HDD27")
		)
		(pad "S1" smd rect
			(at 15.875 -1.82499 270)
			(size 0.6096 2.3622)
			(layers "F.Cu" "F.Mask" "F.Paste")
			(net "GND")
		)
		(pad "S2" smd rect
			(at 14.605 -1.82499 270)
			(size 0.6096 2.3622)
			(layers "F.Cu" "F.Mask" "F.Paste")
			(net "SAS_HDD_RX_P27")
		)
		(pad "S3" smd rect
			(at 13.335 -1.82499 270)
			(size 0.6096 2.3622)
			(layers "F.Cu" "F.Mask" "F.Paste")
			(net "SAS_HDD_RX_N27")
		)
		(pad "S4" smd rect
			(at 12.065 -1.82499 270)
			(size 0.6096 2.3622)
			(layers "F.Cu" "F.Mask" "F.Paste")
			(net "GND")
		)
		(pad "S5" smd rect
			(at 10.795 -1.82499 270)
			(size 0.6096 2.3622)
			(layers "F.Cu" "F.Mask" "F.Paste")
			(net "PHY_DRV_B_TO_SCC_B_27_DN")
		)
		(pad "S6" smd rect
			(at 9.525 -1.82499 270)
			(size 0.6096 2.3622)
			(layers "F.Cu" "F.Mask" "F.Paste")
			(net "PHY_DRV_B_TO_SCC_B_27_DP")
		)
		(pad "S7" smd rect
			(at 8.255 -1.82499 270)
			(size 0.6096 2.3622)
			(layers "F.Cu" "F.Mask" "F.Paste")
			(net "GND")
		)
		(pad "S8" smd rect
			(at 7.480046 2.845054 270)
			(size 0.508 2.3622)
			(layers "F.Cu" "F.Mask" "F.Paste")
			(net "GND")
		)
		(pad "S9" smd rect
			(at 6.679946 2.845054 270)
			(size 0.508 2.3622)
			(layers "F.Cu" "F.Mask" "F.Paste")
			(net "Net_451")
		)
		(pad "S10" smd rect
			(at 5.8801 2.845054 270)
			(size 0.508 2.3622)
			(layers "F.Cu" "F.Mask" "F.Paste")
			(net "Net_343")
		)
		(pad "S11" smd rect
			(at 5.08 2.845054 270)
			(size 0.508 2.3622)
			(layers "F.Cu" "F.Mask" "F.Paste")
			(net "GND")
		)
		(pad "S12" smd rect
			(at 4.2799 2.845054 270)
			(size 0.508 2.3622)
			(layers "F.Cu" "F.Mask" "F.Paste")
			(net "Net_379")
		)
		(pad "S13" smd rect
			(at 3.480054 2.845054 270)
			(size 0.508 2.3622)
			(layers "F.Cu" "F.Mask" "F.Paste")
			(net "Net_415")
		)
		(pad "S14" smd rect
			(at 2.679954 2.845054 270)
			(size 0.508 2.3622)
			(layers "F.Cu" "F.Mask" "F.Paste")
			(net "GND")
		)
		(zone
			(layer "F.Cu")
			(hatch none 0.5)
			(connect_pads
				(clearance 0)
			)
			(min_thickness 0.25)
			(keepout
				(tracks not_allowed)
				(vias allowed)
				(pads allowed)
				(copperpour not_allowed)
				(footprints allowed)
			)
			(placement
				(enabled no)
				(sheetname "")
			)
			(fill
				(thermal_gap 0.5)
				(thermal_bridge_width 0.5)
				(island_removal_mode 0)
			)
			(polygon
				(pts
					(xy 126.507494 -45.648626) (xy 119.433594 -45.648626) (xy 119.433594 -52.582826) (xy 120.538494 -52.582826)
					(xy 120.538494 -48.468026) (xy 125.161294 -48.468026) (xy 125.161294 -52.582826) (xy 126.507494 -52.582826)
				)
			)
		)
		(zone
			(layer "F.Cu")
			(hatch none 0.5)
			(connect_pads
				(clearance 0)
			)
			(min_thickness 0.25)
			(keepout
				(tracks allowed)
				(vias not_allowed)
				(pads allowed)
				(copperpour not_allowed)
				(footprints allowed)
			)
			(placement
				(enabled no)
				(sheetname "")
			)
			(fill
				(thermal_gap 0.5)
				(thermal_bridge_width 0.5)
				(island_removal_mode 0)
			)
			(polygon
				(pts
					(xy 126.507494 -45.648626) (xy 119.433594 -45.648626) (xy 119.433594 -52.582826) (xy 120.538494 -52.582826)
					(xy 120.538494 -48.468026) (xy 125.161294 -48.468026) (xy 125.161294 -52.582826) (xy 126.507494 -52.582826)
				)
			)
		)
		(zone
			(layer "F.Cu")
			(hatch none 0.5)
			(connect_pads
				(clearance 0)
			)
			(min_thickness 0.25)
			(keepout
				(tracks allowed)
				(vias not_allowed)
				(pads allowed)
				(copperpour not_allowed)
				(footprints allowed)
			)
			(placement
				(enabled no)
				(sheetname "")
			)
			(fill
				(thermal_gap 0.5)
				(thermal_bridge_width 0.5)
				(island_removal_mode 0)
			)
			(polygon
				(pts
					(xy 126.507494 -12.171426) (xy 119.433594 -12.171426) (xy 119.433594 -5.237226) (xy 120.538494 -5.237226)
					(xy 120.538494 -9.352026) (xy 125.161294 -9.352026) (xy 125.161294 -5.237226) (xy 126.507494 -5.237226)
				)
			)
		)
		(zone
			(layer "F.Cu")
			(hatch none 0.5)
			(connect_pads
				(clearance 0)
			)
			(min_thickness 0.25)
			(keepout
				(tracks not_allowed)
				(vias allowed)
				(pads allowed)
				(copperpour not_allowed)
				(footprints allowed)
			)
			(placement
				(enabled no)
				(sheetname "")
			)
			(fill
				(thermal_gap 0.5)
				(thermal_bridge_width 0.5)
				(island_removal_mode 0)
			)
			(polygon
				(pts
					(xy 126.507494 -12.171426) (xy 119.433594 -12.171426) (xy 119.433594 -5.237226) (xy 120.538494 -5.237226)
					(xy 120.538494 -9.352026) (xy 125.161294 -9.352026) (xy 125.161294 -5.237226) (xy 126.507494 -5.237226)
				)
			)
		)
		(zone
			(layers "F.Cu" "B.Cu" "In1.Cu" "In2.Cu" "In3.Cu" "In4.Cu" "In5.Cu" "In6.Cu")
			(hatch none 0.5)
			(connect_pads
				(clearance 0)
			)
			(min_thickness 0.25)
			(keepout
				(tracks not_allowed)
				(vias allowed)
				(pads allowed)
				(copperpour not_allowed)
				(footprints allowed)
			)
			(placement
				(enabled no)
				(sheetname "")
			)
			(fill
				(thermal_gap 0.5)
				(thermal_bridge_width 0.5)
				(island_removal_mode 0)
			)
			(polygon
				(pts
					(arc
						(start 123.624594 -10.035032)
						(mid 122.075194 -10.035032)
						(end 123.624594 -10.035032)
					)
				)
			)
		)
		(zone
			(layers "F.Cu" "B.Cu" "In1.Cu" "In2.Cu" "In3.Cu" "In4.Cu" "In5.Cu" "In6.Cu")
			(hatch none 0.5)
			(connect_pads
				(clearance 0)
			)
			(min_thickness 0.25)
			(keepout
				(tracks not_allowed)
				(vias allowed)
				(pads allowed)
				(copperpour not_allowed)
				(footprints allowed)
			)
			(placement
				(enabled no)
				(sheetname "")
			)
			(fill
				(thermal_gap 0.5)
				(thermal_bridge_width 0.5)
				(island_removal_mode 0)
			)
			(polygon
				(pts
					(arc
						(start 123.827794 -47.78502)
						(mid 121.871994 -47.78502)
						(end 123.827794 -47.78502)
					)
				)
			)
		)
	)
	(footprint ""
		(layer "F.Cu")
		(at 370.205 -28.829 90)
		(property "Reference" "C442"
			(at 0 0 90)
			(layer "F.SilkS")
			(hide yes)
			(effects
				(font
					(size 1.27 1.27)
				)
			)
		)
		(property "Value" "SCD033U25V2KX-GP"
			(at 1.1811 -2.7051 90)
			(unlocked yes)
			(layer "F.Fab")
			(hide yes)
			(effects
				(font
					(size 1.016 1.016)
					(thickness 0.1524)
				)
			)
		)
		(property "Device Type" "C402H22"
			(at 1.1811 -4.2291 90)
			(unlocked yes)
			(layer "F.Fab")
			(hide yes)
			(effects
				(font
					(size 1.016 1.016)
					(thickness 0.1524)
				)
			)
		)
		(duplicate_pad_numbers_are_jumpers no)
		(fp_rect
			(start -0.4318 0.9525)
			(end 0.4318 -0.9525)
			(stroke
				(width 0)
				(type default)
			)
			(fill no)
			(layer "F.CrtYd")
		)
		(fp_rect
			(start -0.4318 0.9525)
			(end 0.4318 -0.9525)
			(stroke
				(width 0)
				(type default)
			)
			(fill no)
			(layer "F.Fab")
		)
		(pad "1" smd custom
			(at 0 -0.4445 90)
			(size 0.1524 0.1524)
			(layers "F.Cu" "F.Mask" "F.Paste")
			(net "P12V_B")
			(options
				(clearance outline)
				(anchor circle)
			)
			(primitives
				(gr_poly
					(pts
						(arc
							(start 0.3048 -0.2032)
							(mid 0.275042 -0.275042)
							(end 0.2032 -0.3048)
						)
						(arc
							(start -0.2032 -0.3048)
							(mid -0.275042 -0.275042)
							(end -0.3048 -0.2032)
						)
						(arc
							(start -0.3048 0.2032)
							(mid -0.275042 0.275042)
							(end -0.2032 0.3048)
						)
						(arc
							(start 0.2032 0.3048)
							(mid 0.275042 0.275042)
							(end 0.3048 0.2032)
						)
					)
					(width 0)
					(fill yes)
				)
			)
		)
		(pad "2" smd custom
			(at 0 0.4445 90)
			(size 0.1524 0.1524)
			(layers "F.Cu" "F.Mask" "F.Paste")
			(net "SW_HDD_N31")
			(options
				(clearance outline)
				(anchor circle)
			)
			(primitives
				(gr_poly
					(pts
						(arc
							(start 0.3048 -0.2032)
							(mid 0.275042 -0.275042)
							(end 0.2032 -0.3048)
						)
						(arc
							(start -0.2032 -0.3048)
							(mid -0.275042 -0.275042)
							(end -0.3048 -0.2032)
						)
						(arc
							(start -0.3048 0.2032)
							(mid -0.275042 0.275042)
							(end -0.2032 0.3048)
						)
						(arc
							(start 0.2032 0.3048)
							(mid 0.275042 0.275042)
							(end 0.3048 0.2032)
						)
					)
					(width 0)
					(fill yes)
				)
			)
		)
	)
)
